(kicad_pcb
	(version 20260206)
	(generator "pcbnew")
	(generator_version "10.0")
	(general
		(thickness 1.6)
		(legacy_teardrops no)
	)
	(paper "A4")
	(title_block
		(title "04192023_DAF0TMB3IC0_F0TG_MB_C_brd_V02_OCP.brd")
		(comment 1 "Grand Teton / footprint 3955 of 8354 (U25), pads 3889-3999 of 6102")
	)
	(layers
		(0 "F.Cu" signal "TOP")
		(4 "In1.Cu" signal "GND")
		(6 "In2.Cu" signal "IN1")
		(8 "In3.Cu" signal "GND1")
		(10 "In4.Cu" signal "IN2")
		(12 "In5.Cu" signal "GND2")
		(14 "In6.Cu" signal "IN3")
		(16 "In7.Cu" signal "GND3")
		(18 "In8.Cu" signal "VCC")
		(20 "In9.Cu" signal "VCC1")
		(22 "In10.Cu" signal "GND4")
		(24 "In11.Cu" signal "IN4")
		(26 "In12.Cu" signal "GND5")
		(28 "In13.Cu" signal "IN5")
		(30 "In14.Cu" signal "GND6")
		(32 "In15.Cu" signal "IN6")
		(34 "In16.Cu" signal "GND7")
		(2 "B.Cu" signal "BOTTOM")
		(9 "F.Adhes" user "F.Adhesive")
		(11 "B.Adhes" user "B.Adhesive")
		(13 "F.Paste" user "Package Geometry/Pastemask Top")
		(15 "B.Paste" user "Package Geometry/Pastemask Bottom")
		(5 "F.SilkS" user "Ref Des/Silkscreen Top")
		(7 "B.SilkS" user "Ref Des/Silkscreen Bottom")
		(1 "F.Mask" user "Board Geometry/Soldermask Top")
		(3 "B.Mask" user "Board Geometry/Soldermask Bottom")
		(17 "Dwgs.User" user "User.Drawings")
		(19 "Cmts.User" user "User.Comments")
		(21 "Eco1.User" user "User.Eco1")
		(23 "Eco2.User" user "User.Eco2")
		(25 "Edge.Cuts" user "Board Geometry/Outline")
		(27 "Margin" user)
		(31 "F.CrtYd" user "Package Geometry/Place Bound Top")
		(29 "B.CrtYd" user "Package Geometry/Place Bound Bottom")
		(35 "F.Fab" user "Ref Des/Assembly Top")
		(33 "B.Fab" user "Ref Des/Assembly Bottom")
	)
	(footprint ""
		(layer "F.Cu")
		(at 359.867962 -258.880102 180)
		(property "Reference" "U25"
			(at -45.78477 -62.086744 0)
			(unlocked yes)
			(layer "F.SilkS")
			(effects
				(font
					(size 0.7874 0.5842)
					(thickness 0.1524)
				)
			)
		)
		(property "Value" ""
			(at 0 0 180)
			(layer "F.Fab")
			(effects
				(font
					(size 1.27 1.27)
				)
			)
		)
		(duplicate_pad_numbers_are_jumpers no)
		(pad "CT2" smd circle
			(at -33.990026 26.28011 180)
			(size 0.450088 0.450088)
			(layers "F.Cu" "F.Mask" "F.Paste")
			(net "M_G_CPU0_SB_DQS_DP<2>")
		)
		(pad "CT3" smd circle
			(at -33.049972 26.28011 180)
			(size 0.450088 0.450088)
			(layers "F.Cu" "F.Mask" "F.Paste")
			(net "GND")
		)
		(pad "CT4" smd circle
			(at -32.109918 26.28011 180)
			(size 0.450088 0.450088)
			(layers "F.Cu" "F.Mask" "F.Paste")
			(net "M_G_CPU0_SB_DQ<19>")
		)
		(pad "CT5" smd circle
			(at -31.170118 26.28011 180)
			(size 0.450088 0.450088)
			(layers "F.Cu" "F.Mask" "F.Paste")
			(net "PVDD11_S3_P0")
		)
		(pad "CT6" smd circle
			(at -30.230064 26.28011 180)
			(size 0.450088 0.450088)
			(layers "F.Cu" "F.Mask" "F.Paste")
			(net "M_K_CPU0_SB_DQS_DP<2>")
		)
		(pad "CT7" smd circle
			(at -29.29001 26.28011 180)
			(size 0.450088 0.450088)
			(layers "F.Cu" "F.Mask" "F.Paste")
			(net "M_K_CPU0_SB_DQ<19>")
		)
		(pad "CT8" smd circle
			(at -28.349956 26.28011 180)
			(size 0.450088 0.450088)
			(layers "F.Cu" "F.Mask" "F.Paste")
			(net "GND")
		)
		(pad "CT9" smd circle
			(at -27.409902 26.28011 180)
			(size 0.450088 0.450088)
			(layers "F.Cu" "F.Mask" "F.Paste")
			(net "M_L_CPU0_SB_DQS_DP<2>")
		)
		(pad "CT10" smd circle
			(at -26.470102 26.28011 180)
			(size 0.450088 0.450088)
			(layers "F.Cu" "F.Mask" "F.Paste")
			(net "GND")
		)
		(pad "CT11" smd circle
			(at -25.530048 26.28011 180)
			(size 0.450088 0.450088)
			(layers "F.Cu" "F.Mask" "F.Paste")
			(net "M_L_CPU0_SB_DQ<19>")
		)
		(pad "CT12" smd circle
			(at -24.589994 26.28011 180)
			(size 0.450088 0.450088)
			(layers "F.Cu" "F.Mask" "F.Paste")
			(net "PVDD11_S3_P0")
		)
		(pad "CT13" smd circle
			(at -23.64994 26.28011 180)
			(size 0.450088 0.450088)
			(layers "F.Cu" "F.Mask" "F.Paste")
			(net "M_H_CPU0_SB_DQS_DP<2>")
		)
		(pad "CT14" smd circle
			(at -22.709886 26.28011 180)
			(size 0.450088 0.450088)
			(layers "F.Cu" "F.Mask" "F.Paste")
			(net "M_H_CPU0_SB_DQ<19>")
		)
		(pad "CT15" smd circle
			(at -21.770086 26.28011 180)
			(size 0.450088 0.450088)
			(layers "F.Cu" "F.Mask" "F.Paste")
			(net "GND")
		)
		(pad "CT16" smd circle
			(at -20.830032 26.28011 180)
			(size 0.450088 0.450088)
			(layers "F.Cu" "F.Mask" "F.Paste")
			(net "M_J_CPU0_SB_DQS_DP<2>")
		)
		(pad "CT17" smd circle
			(at -19.889978 26.28011 180)
			(size 0.450088 0.450088)
			(layers "F.Cu" "F.Mask" "F.Paste")
			(net "GND")
		)
		(pad "CT18" smd circle
			(at -18.949924 26.28011 180)
			(size 0.450088 0.450088)
			(layers "F.Cu" "F.Mask" "F.Paste")
			(net "M_J_CPU0_SB_DQ<19>")
		)
		(pad "CT19" smd circle
			(at -18.010124 26.28011 180)
			(size 0.450088 0.450088)
			(layers "F.Cu" "F.Mask" "F.Paste")
			(net "PVDD11_S3_P0")
		)
		(pad "CT20" smd circle
			(at -17.07007 26.28011 180)
			(size 0.450088 0.450088)
			(layers "F.Cu" "F.Mask" "F.Paste")
			(net "M_I_CPU0_SB_DQS_DP<2>")
		)
		(pad "CT21" smd circle
			(at -16.130016 26.28011 180)
			(size 0.450088 0.450088)
			(layers "F.Cu" "F.Mask" "F.Paste")
			(net "M_I_CPU0_SB_DQ<19>")
		)
		(pad "CT22" smd circle
			(at -15.189962 26.28011 180)
			(size 0.450088 0.450088)
			(layers "F.Cu" "F.Mask" "F.Paste")
			(net "PVDD11_S3_P0")
		)
		(pad "CT23" smd circle
			(at -14.249908 26.28011 180)
			(size 0.450088 0.450088)
			(layers "F.Cu" "F.Mask" "F.Paste")
			(net "GND")
		)
		(pad "CT24" smd circle
			(at -13.310108 26.28011 180)
			(size 0.450088 0.450088)
			(layers "F.Cu" "F.Mask" "F.Paste")
			(net "GND")
		)
		(pad "CT25" smd circle
			(at -12.370054 26.28011 180)
			(size 0.450088 0.450088)
			(layers "F.Cu" "F.Mask" "F.Paste")
			(net "GND")
		)
		(pad "CT26" smd circle
			(at -11.43 26.28011 180)
			(size 0.450088 0.450088)
			(layers "F.Cu" "F.Mask" "F.Paste")
			(net "GND")
		)
		(pad "CT27" smd circle
			(at -10.489946 26.28011 180)
			(size 0.450088 0.450088)
			(layers "F.Cu" "F.Mask" "F.Paste")
			(net "GND")
		)
		(pad "CT28" smd circle
			(at -9.549892 26.28011 180)
			(size 0.450088 0.450088)
			(layers "F.Cu" "F.Mask" "F.Paste")
			(net "GND")
		)
		(pad "CT29" smd circle
			(at -8.610092 26.28011 180)
			(size 0.450088 0.450088)
			(layers "F.Cu" "F.Mask" "F.Paste")
			(net "GND")
		)
		(pad "CT30" smd circle
			(at -7.670038 26.28011 180)
			(size 0.450088 0.450088)
			(layers "F.Cu" "F.Mask" "F.Paste")
			(net "GND")
		)
		(pad "CT31" smd circle
			(at -6.729984 26.28011 180)
			(size 0.450088 0.450088)
			(layers "F.Cu" "F.Mask" "F.Paste")
			(net "GND")
		)
		(pad "CT32" smd circle
			(at -5.78993 26.28011 180)
			(size 0.450088 0.450088)
			(layers "F.Cu" "F.Mask" "F.Paste")
			(net "GND")
		)
		(pad "CT33" smd circle
			(at -4.849876 26.28011 180)
			(size 0.450088 0.450088)
			(layers "F.Cu" "F.Mask" "F.Paste")
			(net "GND")
		)
		(pad "CT34" smd circle
			(at -3.910076 26.28011 180)
			(size 0.450088 0.450088)
			(layers "F.Cu" "F.Mask" "F.Paste")
			(net "GND")
		)
		(pad "CT35" smd circle
			(at -2.970022 26.28011 180)
			(size 0.450088 0.450088)
			(layers "F.Cu" "F.Mask" "F.Paste")
			(net "P5E_CPU0_P2_RX_DP<2>")
		)
		(pad "CT36" smd circle
			(at -2.029968 26.28011 180)
			(size 0.450088 0.450088)
			(layers "F.Cu" "F.Mask" "F.Paste")
			(net "P5E_CPU0_P2_RX_DN<2>")
		)
		(pad "CT37" smd circle
			(at -1.089914 26.28011 180)
			(size 0.450088 0.450088)
			(layers "F.Cu" "F.Mask" "F.Paste")
			(net "GND")
		)
		(pad "CT39" smd circle
			(at 0.78994 26.28011 180)
			(size 0.450088 0.450088)
			(layers "F.Cu" "F.Mask" "F.Paste")
			(net "GND")
		)
		(pad "CT40" smd circle
			(at 1.729994 26.28011 180)
			(size 0.450088 0.450088)
			(layers "F.Cu" "F.Mask" "F.Paste")
			(net "P5E_CPU0_P0_TX_DN<13>")
		)
		(pad "CT41" smd circle
			(at 2.670048 26.28011 180)
			(size 0.450088 0.450088)
			(layers "F.Cu" "F.Mask" "F.Paste")
			(net "P5E_CPU0_P0_TX_DP<13>")
		)
		(pad "CT42" smd circle
			(at 3.610102 26.28011 180)
			(size 0.450088 0.450088)
			(layers "F.Cu" "F.Mask" "F.Paste")
			(net "GND")
		)
		(pad "CT43" smd circle
			(at 4.549902 26.28011 180)
			(size 0.450088 0.450088)
			(layers "F.Cu" "F.Mask" "F.Paste")
			(net "GND")
		)
		(pad "CT44" smd circle
			(at 5.489956 26.28011 180)
			(size 0.450088 0.450088)
			(layers "F.Cu" "F.Mask" "F.Paste")
			(net "GND")
		)
		(pad "CT45" smd circle
			(at 6.43001 26.28011 180)
			(size 0.450088 0.450088)
			(layers "F.Cu" "F.Mask" "F.Paste")
			(net "GND")
		)
		(pad "CT46" smd circle
			(at 7.370064 26.28011 180)
			(size 0.450088 0.450088)
			(layers "F.Cu" "F.Mask" "F.Paste")
			(net "GND")
		)
		(pad "CT47" smd circle
			(at 8.310118 26.28011 180)
			(size 0.450088 0.450088)
			(layers "F.Cu" "F.Mask" "F.Paste")
			(net "GND")
		)
		(pad "CT48" smd circle
			(at 9.249918 26.28011 180)
			(size 0.450088 0.450088)
			(layers "F.Cu" "F.Mask" "F.Paste")
			(net "GND")
		)
		(pad "CT49" smd circle
			(at 10.189972 26.28011 180)
			(size 0.450088 0.450088)
			(layers "F.Cu" "F.Mask" "F.Paste")
			(net "GND")
		)
		(pad "CT50" smd circle
			(at 11.130026 26.28011 180)
			(size 0.450088 0.450088)
			(layers "F.Cu" "F.Mask" "F.Paste")
			(net "GND")
		)
		(pad "CT51" smd circle
			(at 12.07008 26.28011 180)
			(size 0.450088 0.450088)
			(layers "F.Cu" "F.Mask" "F.Paste")
			(net "GND")
		)
		(pad "CT52" smd circle
			(at 13.00988 26.28011 180)
			(size 0.450088 0.450088)
			(layers "F.Cu" "F.Mask" "F.Paste")
			(net "GND")
		)
		(pad "CT53" smd circle
			(at 13.949934 26.28011 180)
			(size 0.450088 0.450088)
			(layers "F.Cu" "F.Mask" "F.Paste")
			(net "GND")
		)
		(pad "CT54" smd circle
			(at 14.889988 26.28011 180)
			(size 0.450088 0.450088)
			(layers "F.Cu" "F.Mask" "F.Paste")
			(net "PVDDIO_P0")
		)
		(pad "CT55" smd circle
			(at 15.830042 26.28011 180)
			(size 0.450088 0.450088)
			(layers "F.Cu" "F.Mask" "F.Paste")
			(net "M_C_CPU0_SB_DQ<19>")
		)
		(pad "CT56" smd circle
			(at 16.770096 26.28011 180)
			(size 0.450088 0.450088)
			(layers "F.Cu" "F.Mask" "F.Paste")
			(net "M_C_CPU0_SB_DQS_DP<2>")
		)
		(pad "CT57" smd circle
			(at 17.709896 26.28011 180)
			(size 0.450088 0.450088)
			(layers "F.Cu" "F.Mask" "F.Paste")
			(net "PVDDIO_P0")
		)
		(pad "CT58" smd circle
			(at 18.64995 26.28011 180)
			(size 0.450088 0.450088)
			(layers "F.Cu" "F.Mask" "F.Paste")
			(net "M_D_CPU0_SB_DQ<19>")
		)
		(pad "CT59" smd circle
			(at 19.590004 26.28011 180)
			(size 0.450088 0.450088)
			(layers "F.Cu" "F.Mask" "F.Paste")
			(net "GND")
		)
		(pad "CT60" smd circle
			(at 20.530058 26.28011 180)
			(size 0.450088 0.450088)
			(layers "F.Cu" "F.Mask" "F.Paste")
			(net "M_D_CPU0_SB_DQS_DP<2>")
		)
		(pad "CT61" smd circle
			(at 21.470112 26.28011 180)
			(size 0.450088 0.450088)
			(layers "F.Cu" "F.Mask" "F.Paste")
			(net "GND")
		)
		(pad "CT62" smd circle
			(at 22.409912 26.28011 180)
			(size 0.450088 0.450088)
			(layers "F.Cu" "F.Mask" "F.Paste")
			(net "M_B_CPU0_SB_DQ<19>")
		)
		(pad "CT63" smd circle
			(at 23.349966 26.28011 180)
			(size 0.450088 0.450088)
			(layers "F.Cu" "F.Mask" "F.Paste")
			(net "M_B_CPU0_SB_DQS_DP<2>")
		)
		(pad "CT64" smd circle
			(at 24.29002 26.28011 180)
			(size 0.450088 0.450088)
			(layers "F.Cu" "F.Mask" "F.Paste")
			(net "PVDDIO_P0")
		)
		(pad "CT65" smd circle
			(at 25.230074 26.28011 180)
			(size 0.450088 0.450088)
			(layers "F.Cu" "F.Mask" "F.Paste")
			(net "M_F_CPU0_SB_DQ<19>")
		)
		(pad "CT66" smd circle
			(at 26.170128 26.28011 180)
			(size 0.450088 0.450088)
			(layers "F.Cu" "F.Mask" "F.Paste")
			(net "GND")
		)
		(pad "CT67" smd circle
			(at 27.109928 26.28011 180)
			(size 0.450088 0.450088)
			(layers "F.Cu" "F.Mask" "F.Paste")
			(net "M_F_CPU0_SB_DQS_DP<2>")
		)
		(pad "CT68" smd circle
			(at 28.049982 26.28011 180)
			(size 0.450088 0.450088)
			(layers "F.Cu" "F.Mask" "F.Paste")
			(net "GND")
		)
		(pad "CT69" smd circle
			(at 28.990036 26.28011 180)
			(size 0.450088 0.450088)
			(layers "F.Cu" "F.Mask" "F.Paste")
			(net "M_E_CPU0_SB_DQ<19>")
		)
		(pad "CT70" smd circle
			(at 29.93009 26.28011 180)
			(size 0.450088 0.450088)
			(layers "F.Cu" "F.Mask" "F.Paste")
			(net "M_E_CPU0_SB_DQS_DP<2>")
		)
		(pad "CT71" smd circle
			(at 30.86989 26.28011 180)
			(size 0.450088 0.450088)
			(layers "F.Cu" "F.Mask" "F.Paste")
			(net "PVDDIO_P0")
		)
		(pad "CT72" smd circle
			(at 31.809944 26.28011 180)
			(size 0.450088 0.450088)
			(layers "F.Cu" "F.Mask" "F.Paste")
			(net "M_A_CPU0_SB_DQ<19>")
		)
		(pad "CT73" smd circle
			(at 32.749998 26.28011 180)
			(size 0.450088 0.450088)
			(layers "F.Cu" "F.Mask" "F.Paste")
			(net "GND")
		)
		(pad "CT74" smd circle
			(at 33.690052 26.28011 180)
			(size 0.450088 0.450088)
			(layers "F.Cu" "F.Mask" "F.Paste")
			(net "M_A_CPU0_SB_DQS_DP<2>")
		)
		(pad "CU1" smd circle
			(at -34.459926 27.090116 180)
			(size 0.450088 0.450088)
			(layers "F.Cu" "F.Mask" "F.Paste")
			(net "GND")
		)
		(pad "CU2" smd circle
			(at -33.519872 27.090116 180)
			(size 0.450088 0.450088)
			(layers "F.Cu" "F.Mask" "F.Paste")
			(net "M_G_CPU0_SB_DQS_DN<2>")
		)
		(pad "CU3" smd circle
			(at -32.580072 27.090116 180)
			(size 0.450088 0.450088)
			(layers "F.Cu" "F.Mask" "F.Paste")
			(net "M_G_CPU0_SB_DQS_DN<7>")
		)
		(pad "CU4" smd circle
			(at -31.640018 27.090116 180)
			(size 0.450088 0.450088)
			(layers "F.Cu" "F.Mask" "F.Paste")
			(net "GND")
		)
		(pad "CU5" smd circle
			(at -30.699964 27.090116 180)
			(size 0.450088 0.450088)
			(layers "F.Cu" "F.Mask" "F.Paste")
			(net "M_K_CPU0_SB_DQS_DN<2>")
		)
		(pad "CU6" smd circle
			(at -29.75991 27.090116 180)
			(size 0.450088 0.450088)
			(layers "F.Cu" "F.Mask" "F.Paste")
			(net "GND")
		)
		(pad "CU7" smd circle
			(at -28.82011 27.090116 180)
			(size 0.450088 0.450088)
			(layers "F.Cu" "F.Mask" "F.Paste")
			(net "M_K_CPU0_SB_DQS_DN<7>")
		)
		(pad "CU8" smd circle
			(at -27.880056 27.090116 180)
			(size 0.450088 0.450088)
			(layers "F.Cu" "F.Mask" "F.Paste")
			(net "GND")
		)
		(pad "CU9" smd circle
			(at -26.940002 27.090116 180)
			(size 0.450088 0.450088)
			(layers "F.Cu" "F.Mask" "F.Paste")
			(net "M_L_CPU0_SB_DQS_DN<2>")
		)
		(pad "CU10" smd circle
			(at -25.999948 27.090116 180)
			(size 0.450088 0.450088)
			(layers "F.Cu" "F.Mask" "F.Paste")
			(net "M_L_CPU0_SB_DQS_DN<7>")
		)
		(pad "CU11" smd circle
			(at -25.059894 27.090116 180)
			(size 0.450088 0.450088)
			(layers "F.Cu" "F.Mask" "F.Paste")
			(net "GND")
		)
		(pad "CU12" smd circle
			(at -24.120094 27.090116 180)
			(size 0.450088 0.450088)
			(layers "F.Cu" "F.Mask" "F.Paste")
			(net "M_H_CPU0_SB_DQS_DN<2>")
		)
		(pad "CU13" smd circle
			(at -23.18004 27.090116 180)
			(size 0.450088 0.450088)
			(layers "F.Cu" "F.Mask" "F.Paste")
			(net "GND")
		)
		(pad "CU14" smd circle
			(at -22.239986 27.090116 180)
			(size 0.450088 0.450088)
			(layers "F.Cu" "F.Mask" "F.Paste")
			(net "M_H_CPU0_SB_DQS_DN<7>")
		)
		(pad "CU15" smd circle
			(at -21.299932 27.090116 180)
			(size 0.450088 0.450088)
			(layers "F.Cu" "F.Mask" "F.Paste")
			(net "GND")
		)
		(pad "CU16" smd circle
			(at -20.359878 27.090116 180)
			(size 0.450088 0.450088)
			(layers "F.Cu" "F.Mask" "F.Paste")
			(net "M_J_CPU0_SB_DQS_DN<2>")
		)
		(pad "CU17" smd circle
			(at -19.420078 27.090116 180)
			(size 0.450088 0.450088)
			(layers "F.Cu" "F.Mask" "F.Paste")
			(net "M_J_CPU0_SB_DQS_DN<7>")
		)
		(pad "CU18" smd circle
			(at -18.480024 27.090116 180)
			(size 0.450088 0.450088)
			(layers "F.Cu" "F.Mask" "F.Paste")
			(net "GND")
		)
		(pad "CU19" smd circle
			(at -17.53997 27.090116 180)
			(size 0.450088 0.450088)
			(layers "F.Cu" "F.Mask" "F.Paste")
			(net "M_I_CPU0_SB_DQS_DN<2>")
		)
		(pad "CU20" smd circle
			(at -16.599916 27.090116 180)
			(size 0.450088 0.450088)
			(layers "F.Cu" "F.Mask" "F.Paste")
			(net "GND")
		)
		(pad "CU21" smd circle
			(at -15.660116 27.090116 180)
			(size 0.450088 0.450088)
			(layers "F.Cu" "F.Mask" "F.Paste")
			(net "M_I_CPU0_SB_DQS_DN<7>")
		)
		(pad "CU22" smd circle
			(at -14.720062 27.090116 180)
			(size 0.450088 0.450088)
			(layers "F.Cu" "F.Mask" "F.Paste")
			(net "GND")
		)
		(pad "CU23" smd circle
			(at -13.780008 27.090116 180)
			(size 0.450088 0.450088)
			(layers "F.Cu" "F.Mask" "F.Paste")
			(net "P5E_CPU0_P3_RX_DP<15>")
		)
		(pad "CU24" smd circle
			(at -12.839954 27.090116 180)
			(size 0.450088 0.450088)
			(layers "F.Cu" "F.Mask" "F.Paste")
			(net "P5E_CPU0_P3_RX_DN<15>")
		)
		(pad "CU25" smd circle
			(at -11.8999 27.090116 180)
			(size 0.450088 0.450088)
			(layers "F.Cu" "F.Mask" "F.Paste")
			(net "GND")
		)
		(pad "CU26" smd circle
			(at -10.9601 27.090116 180)
			(size 0.450088 0.450088)
			(layers "F.Cu" "F.Mask" "F.Paste")
			(net "P5E_CPU0_P2_RX_DP<10>")
		)
		(pad "CU27" smd circle
			(at -10.020046 27.090116 180)
			(size 0.450088 0.450088)
			(layers "F.Cu" "F.Mask" "F.Paste")
			(net "P5E_CPU0_P2_RX_DN<10>")
		)
		(pad "CU28" smd circle
			(at -9.079992 27.090116 180)
			(size 0.450088 0.450088)
			(layers "F.Cu" "F.Mask" "F.Paste")
			(net "GND")
		)
		(pad "CU29" smd circle
			(at -8.139938 27.090116 180)
			(size 0.450088 0.450088)
			(layers "F.Cu" "F.Mask" "F.Paste")
			(net "P5E_CPU0_P2_RX_DP<7>")
		)
		(pad "CU30" smd circle
			(at -7.199884 27.090116 180)
			(size 0.450088 0.450088)
			(layers "F.Cu" "F.Mask" "F.Paste")
			(net "P5E_CPU0_P2_RX_DN<7>")
		)
		(pad "CU31" smd circle
			(at -6.260084 27.090116 180)
			(size 0.450088 0.450088)
			(layers "F.Cu" "F.Mask" "F.Paste")
			(net "GND")
		)
		(pad "CU32" smd circle
			(at -5.32003 27.090116 180)
			(size 0.450088 0.450088)
			(layers "F.Cu" "F.Mask" "F.Paste")
			(net "P5E_CPU0_P2_RX_DP<4>")
		)
		(pad "CU33" smd circle
			(at -4.379976 27.090116 180)
			(size 0.450088 0.450088)
			(layers "F.Cu" "F.Mask" "F.Paste")
			(net "P5E_CPU0_P2_RX_DN<4>")
		)
		(pad "CU34" smd circle
			(at -3.439922 27.090116 180)
			(size 0.450088 0.450088)
			(layers "F.Cu" "F.Mask" "F.Paste")
			(net "GND")
		)
		(pad "CU35" smd circle
			(at -2.500122 27.090116 180)
			(size 0.450088 0.450088)
			(layers "F.Cu" "F.Mask" "F.Paste")
			(net "PVDDCR_CPU1_P0")
		)
		(pad "CU36" smd circle
			(at -1.560068 27.090116 180)
			(size 0.450088 0.450088)
			(layers "F.Cu" "F.Mask" "F.Paste")
			(net "PVDDCR_CPU1_P0")
		)
		(pad "CU40" smd circle
			(at 1.260094 27.090116 180)
			(size 0.450088 0.450088)
			(layers "F.Cu" "F.Mask" "F.Paste")
			(net "PVDDCR_CPU1_P0")
		)
		(pad "CU41" smd circle
			(at 2.199894 27.090116 180)
			(size 0.450088 0.450088)
			(layers "F.Cu" "F.Mask" "F.Paste")
			(net "PVDDCR_CPU1_P0")
		)
		(pad "CU42" smd circle
			(at 3.139948 27.090116 180)
			(size 0.450088 0.450088)
			(layers "F.Cu" "F.Mask" "F.Paste")
			(net "GND")
		)
	)
)
